(kicad_pcb
	(version 20260206)
	(generator "pcbnew")
	(generator_version "10.0")
	(general
		(thickness 1.6)
		(legacy_teardrops no)
	)
	(paper "A4")
	(title_block
		(title "04192023_DAF0TMB3IC0_F0TG_MB_C_brd_V02_OCP.brd")
		(comment 1 "Grand Teton / footprints 2869-2872 of 8354")
	)
	(layers
		(0 "F.Cu" signal "TOP")
		(4 "In1.Cu" signal "GND")
		(6 "In2.Cu" signal "IN1")
		(8 "In3.Cu" signal "GND1")
		(10 "In4.Cu" signal "IN2")
		(12 "In5.Cu" signal "GND2")
		(14 "In6.Cu" signal "IN3")
		(16 "In7.Cu" signal "GND3")
		(18 "In8.Cu" signal "VCC")
		(20 "In9.Cu" signal "VCC1")
		(22 "In10.Cu" signal "GND4")
		(24 "In11.Cu" signal "IN4")
		(26 "In12.Cu" signal "GND5")
		(28 "In13.Cu" signal "IN5")
		(30 "In14.Cu" signal "GND6")
		(32 "In15.Cu" signal "IN6")
		(34 "In16.Cu" signal "GND7")
		(2 "B.Cu" signal "BOTTOM")
		(9 "F.Adhes" user "F.Adhesive")
		(11 "B.Adhes" user "B.Adhesive")
		(13 "F.Paste" user "Package Geometry/Pastemask Top")
		(15 "B.Paste" user "Package Geometry/Pastemask Bottom")
		(5 "F.SilkS" user "Ref Des/Silkscreen Top")
		(7 "B.SilkS" user "Ref Des/Silkscreen Bottom")
		(1 "F.Mask" user "Board Geometry/Soldermask Top")
		(3 "B.Mask" user "Board Geometry/Soldermask Bottom")
		(17 "Dwgs.User" user "User.Drawings")
		(19 "Cmts.User" user "User.Comments")
		(21 "Eco1.User" user "User.Eco1")
		(23 "Eco2.User" user "User.Eco2")
		(25 "Edge.Cuts" user "Board Geometry/Outline")
		(27 "Margin" user)
		(31 "F.CrtYd" user "Package Geometry/Place Bound Top")
		(29 "B.CrtYd" user "Package Geometry/Place Bound Bottom")
		(35 "F.Fab" user "Ref Des/Assembly Top")
		(33 "B.Fab" user "Ref Des/Assembly Bottom")
	)
	(footprint ""
		(layer "F.Cu")
		(at 338.31022 -15.98803 90)
		(property "Reference" "R948"
			(at 0 0 90)
			(layer "F.SilkS")
			(hide yes)
			(effects
				(font
					(size 1.27 1.27)
				)
			)
		)
		(property "Value" ""
			(at 0 0 90)
			(layer "F.Fab")
			(effects
				(font
					(size 1.27 1.27)
				)
			)
		)
		(duplicate_pad_numbers_are_jumpers no)
		(fp_line
			(start 0.7874 -0.4064)
			(end 0.7874 0.4064)
			(stroke
				(width 0.1524)
				(type default)
			)
			(layer "F.SilkS")
		)
		(fp_line
			(start -0.7874 -0.4064)
			(end 0.7874 -0.4064)
			(stroke
				(width 0.1524)
				(type default)
			)
			(layer "F.SilkS")
		)
		(fp_line
			(start 0.7874 0.4064)
			(end -0.7874 0.4064)
			(stroke
				(width 0.1524)
				(type default)
			)
			(layer "F.SilkS")
		)
		(fp_line
			(start -0.7874 0.4064)
			(end -0.7874 -0.4064)
			(stroke
				(width 0.1524)
				(type default)
			)
			(layer "F.SilkS")
		)
		(fp_line
			(start -0.12065 -0.305054)
			(end -0.12065 -0.2794)
			(stroke
				(width 0.1)
				(type default)
			)
			(layer "F.Fab")
		)
		(fp_line
			(start -0.67945 -0.305054)
			(end -0.12065 -0.305054)
			(stroke
				(width 0.1)
				(type default)
			)
			(layer "F.Fab")
		)
		(fp_line
			(start 0.67945 -0.3048)
			(end 0.67945 0.3048)
			(stroke
				(width 0.1)
				(type default)
			)
			(layer "F.Fab")
		)
		(fp_line
			(start 0.12065 -0.3048)
			(end 0.67945 -0.3048)
			(stroke
				(width 0.1)
				(type default)
			)
			(layer "F.Fab")
		)
		(fp_line
			(start 0.12065 -0.2794)
			(end 0.12065 -0.3048)
			(stroke
				(width 0.1)
				(type default)
			)
			(layer "F.Fab")
		)
		(fp_line
			(start -0.12065 -0.2794)
			(end 0.12065 -0.2794)
			(stroke
				(width 0.1)
				(type default)
			)
			(layer "F.Fab")
		)
		(fp_line
			(start 0.120396 0.2794)
			(end -0.12065 0.2794)
			(stroke
				(width 0.1)
				(type default)
			)
			(layer "F.Fab")
		)
		(fp_line
			(start -0.12065 0.2794)
			(end -0.12065 0.3048)
			(stroke
				(width 0.1)
				(type default)
			)
			(layer "F.Fab")
		)
		(fp_line
			(start 0.67945 0.3048)
			(end 0.120396 0.3048)
			(stroke
				(width 0.1)
				(type default)
			)
			(layer "F.Fab")
		)
		(fp_line
			(start 0.120396 0.3048)
			(end 0.120396 0.2794)
			(stroke
				(width 0.1)
				(type default)
			)
			(layer "F.Fab")
		)
		(fp_line
			(start -0.12065 0.3048)
			(end -0.67945 0.3048)
			(stroke
				(width 0.1)
				(type default)
			)
			(layer "F.Fab")
		)
		(fp_line
			(start -0.67945 0.3048)
			(end -0.67945 -0.305054)
			(stroke
				(width 0.1)
				(type default)
			)
			(layer "F.Fab")
		)
		(pad "1" smd circle
			(at -0.40005 0 90)
			(size 0 0)
			(layers "F.Cu" "F.Mask" "F.Paste")
			(net "PU_BOOT_RDY_LED")
		)
		(pad "2" smd circle
			(at 0.40005 0 90)
			(size 0 0)
			(layers "F.Cu" "F.Mask" "F.Paste")
			(net "P3V3_AUX")
		)
	)
	(footprint ""
		(layer "F.Cu")
		(at 160.174686 -58.15965 -90)
		(property "Reference" "C2021"
			(at 0 0 270)
			(layer "F.SilkS")
			(hide yes)
			(effects
				(font
					(size 1.27 1.27)
				)
			)
		)
		(property "Value" ""
			(at 0 0 270)
			(layer "F.Fab")
			(effects
				(font
					(size 1.27 1.27)
				)
			)
		)
		(duplicate_pad_numbers_are_jumpers no)
		(fp_line
			(start -0.7874 0.4064)
			(end -0.7874 -0.4064)
			(stroke
				(width 0.1524)
				(type default)
			)
			(layer "F.SilkS")
		)
		(fp_line
			(start 0.7874 0.4064)
			(end -0.7874 0.4064)
			(stroke
				(width 0.1524)
				(type default)
			)
			(layer "F.SilkS")
		)
		(fp_line
			(start -0.7874 -0.4064)
			(end 0.7874 -0.4064)
			(stroke
				(width 0.1524)
				(type default)
			)
			(layer "F.SilkS")
		)
		(fp_line
			(start 0.7874 -0.4064)
			(end 0.7874 0.4064)
			(stroke
				(width 0.1524)
				(type default)
			)
			(layer "F.SilkS")
		)
		(fp_line
			(start -0.67945 0.3048)
			(end -0.67945 -0.305054)
			(stroke
				(width 0.1)
				(type default)
			)
			(layer "F.Fab")
		)
		(fp_line
			(start -0.12065 0.3048)
			(end -0.67945 0.3048)
			(stroke
				(width 0.1)
				(type default)
			)
			(layer "F.Fab")
		)
		(fp_line
			(start 0.120396 0.3048)
			(end 0.120396 0.2794)
			(stroke
				(width 0.1)
				(type default)
			)
			(layer "F.Fab")
		)
		(fp_line
			(start 0.67945 0.3048)
			(end 0.120396 0.3048)
			(stroke
				(width 0.1)
				(type default)
			)
			(layer "F.Fab")
		)
		(fp_line
			(start -0.12065 0.2794)
			(end -0.12065 0.3048)
			(stroke
				(width 0.1)
				(type default)
			)
			(layer "F.Fab")
		)
		(fp_line
			(start 0.120396 0.2794)
			(end -0.12065 0.2794)
			(stroke
				(width 0.1)
				(type default)
			)
			(layer "F.Fab")
		)
		(fp_line
			(start -0.12065 -0.2794)
			(end 0.12065 -0.2794)
			(stroke
				(width 0.1)
				(type default)
			)
			(layer "F.Fab")
		)
		(fp_line
			(start 0.12065 -0.2794)
			(end 0.12065 -0.3048)
			(stroke
				(width 0.1)
				(type default)
			)
			(layer "F.Fab")
		)
		(fp_line
			(start 0.12065 -0.3048)
			(end 0.67945 -0.3048)
			(stroke
				(width 0.1)
				(type default)
			)
			(layer "F.Fab")
		)
		(fp_line
			(start 0.67945 -0.3048)
			(end 0.67945 0.3048)
			(stroke
				(width 0.1)
				(type default)
			)
			(layer "F.Fab")
		)
		(fp_line
			(start -0.67945 -0.305054)
			(end -0.12065 -0.305054)
			(stroke
				(width 0.1)
				(type default)
			)
			(layer "F.Fab")
		)
		(fp_line
			(start -0.12065 -0.305054)
			(end -0.12065 -0.2794)
			(stroke
				(width 0.1)
				(type default)
			)
			(layer "F.Fab")
		)
		(pad "1" smd circle
			(at -0.40005 0 270)
			(size 0 0)
			(layers "F.Cu" "F.Mask" "F.Paste")
			(net "VSENSE_P12V_INA230_4_INP")
		)
		(pad "2" smd circle
			(at 0.40005 0 270)
			(size 0 0)
			(layers "F.Cu" "F.Mask" "F.Paste")
			(net "VSENSE_P12V_INA230_4_INN")
		)
	)
	(footprint ""
		(layer "F.Cu")
		(at 13.872464 -15.32128 90)
		(property "Reference" "R3178"
			(at 0 0 90)
			(layer "F.SilkS")
			(hide yes)
			(effects
				(font
					(size 1.27 1.27)
				)
			)
		)
		(property "Value" ""
			(at 0 0 90)
			(layer "F.Fab")
			(effects
				(font
					(size 1.27 1.27)
				)
			)
		)
		(duplicate_pad_numbers_are_jumpers no)
		(fp_line
			(start 0.7874 -0.4064)
			(end 0.7874 0.4064)
			(stroke
				(width 0.1524)
				(type default)
			)
			(layer "F.SilkS")
		)
		(fp_line
			(start -0.7874 -0.4064)
			(end 0.7874 -0.4064)
			(stroke
				(width 0.1524)
				(type default)
			)
			(layer "F.SilkS")
		)
		(fp_line
			(start 0.7874 0.4064)
			(end -0.7874 0.4064)
			(stroke
				(width 0.1524)
				(type default)
			)
			(layer "F.SilkS")
		)
		(fp_line
			(start -0.7874 0.4064)
			(end -0.7874 -0.4064)
			(stroke
				(width 0.1524)
				(type default)
			)
			(layer "F.SilkS")
		)
		(fp_line
			(start -0.12065 -0.305054)
			(end -0.12065 -0.2794)
			(stroke
				(width 0.1)
				(type default)
			)
			(layer "F.Fab")
		)
		(fp_line
			(start -0.67945 -0.305054)
			(end -0.12065 -0.305054)
			(stroke
				(width 0.1)
				(type default)
			)
			(layer "F.Fab")
		)
		(fp_line
			(start 0.67945 -0.3048)
			(end 0.67945 0.3048)
			(stroke
				(width 0.1)
				(type default)
			)
			(layer "F.Fab")
		)
		(fp_line
			(start 0.12065 -0.3048)
			(end 0.67945 -0.3048)
			(stroke
				(width 0.1)
				(type default)
			)
			(layer "F.Fab")
		)
		(fp_line
			(start 0.12065 -0.2794)
			(end 0.12065 -0.3048)
			(stroke
				(width 0.1)
				(type default)
			)
			(layer "F.Fab")
		)
		(fp_line
			(start -0.12065 -0.2794)
			(end 0.12065 -0.2794)
			(stroke
				(width 0.1)
				(type default)
			)
			(layer "F.Fab")
		)
		(fp_line
			(start 0.120396 0.2794)
			(end -0.12065 0.2794)
			(stroke
				(width 0.1)
				(type default)
			)
			(layer "F.Fab")
		)
		(fp_line
			(start -0.12065 0.2794)
			(end -0.12065 0.3048)
			(stroke
				(width 0.1)
				(type default)
			)
			(layer "F.Fab")
		)
		(fp_line
			(start 0.67945 0.3048)
			(end 0.120396 0.3048)
			(stroke
				(width 0.1)
				(type default)
			)
			(layer "F.Fab")
		)
		(fp_line
			(start 0.120396 0.3048)
			(end 0.120396 0.2794)
			(stroke
				(width 0.1)
				(type default)
			)
			(layer "F.Fab")
		)
		(fp_line
			(start -0.12065 0.3048)
			(end -0.67945 0.3048)
			(stroke
				(width 0.1)
				(type default)
			)
			(layer "F.Fab")
		)
		(fp_line
			(start -0.67945 0.3048)
			(end -0.67945 -0.305054)
			(stroke
				(width 0.1)
				(type default)
			)
			(layer "F.Fab")
		)
		(pad "1" smd circle
			(at -0.40005 0 90)
			(size 0 0)
			(layers "F.Cu" "F.Mask" "F.Paste")
			(net "USB2_P10_DP")
		)
		(pad "2" smd circle
			(at 0.40005 0 90)
			(size 0 0)
			(layers "F.Cu" "F.Mask" "F.Paste")
			(net "USB2_CPU0_P10_DP")
		)
	)
	(footprint ""
		(layer "F.Cu")
		(at 340.715346 -23.897336 -90)
		(property "Reference" "R944"
			(at 0 0 270)
			(layer "F.SilkS")
			(hide yes)
			(effects
				(font
					(size 1.27 1.27)
				)
			)
		)
		(property "Value" ""
			(at 0 0 270)
			(layer "F.Fab")
			(effects
				(font
					(size 1.27 1.27)
				)
			)
		)
		(duplicate_pad_numbers_are_jumpers no)
		(fp_line
			(start -0.7874 0.4064)
			(end -0.7874 -0.4064)
			(stroke
				(width 0.1524)
				(type default)
			)
			(layer "F.SilkS")
		)
		(fp_line
			(start 0.7874 0.4064)
			(end -0.7874 0.4064)
			(stroke
				(width 0.1524)
				(type default)
			)
			(layer "F.SilkS")
		)
		(fp_line
			(start -0.7874 -0.4064)
			(end 0.7874 -0.4064)
			(stroke
				(width 0.1524)
				(type default)
			)
			(layer "F.SilkS")
		)
		(fp_line
			(start 0.7874 -0.4064)
			(end 0.7874 0.4064)
			(stroke
				(width 0.1524)
				(type default)
			)
			(layer "F.SilkS")
		)
		(fp_line
			(start -0.67945 0.3048)
			(end -0.67945 -0.305054)
			(stroke
				(width 0.1)
				(type default)
			)
			(layer "F.Fab")
		)
		(fp_line
			(start -0.12065 0.3048)
			(end -0.67945 0.3048)
			(stroke
				(width 0.1)
				(type default)
			)
			(layer "F.Fab")
		)
		(fp_line
			(start 0.120396 0.3048)
			(end 0.120396 0.2794)
			(stroke
				(width 0.1)
				(type default)
			)
			(layer "F.Fab")
		)
		(fp_line
			(start 0.67945 0.3048)
			(end 0.120396 0.3048)
			(stroke
				(width 0.1)
				(type default)
			)
			(layer "F.Fab")
		)
		(fp_line
			(start -0.12065 0.2794)
			(end -0.12065 0.3048)
			(stroke
				(width 0.1)
				(type default)
			)
			(layer "F.Fab")
		)
		(fp_line
			(start 0.120396 0.2794)
			(end -0.12065 0.2794)
			(stroke
				(width 0.1)
				(type default)
			)
			(layer "F.Fab")
		)
		(fp_line
			(start -0.12065 -0.2794)
			(end 0.12065 -0.2794)
			(stroke
				(width 0.1)
				(type default)
			)
			(layer "F.Fab")
		)
		(fp_line
			(start 0.12065 -0.2794)
			(end 0.12065 -0.3048)
			(stroke
				(width 0.1)
				(type default)
			)
			(layer "F.Fab")
		)
		(fp_line
			(start 0.12065 -0.3048)
			(end 0.67945 -0.3048)
			(stroke
				(width 0.1)
				(type default)
			)
			(layer "F.Fab")
		)
		(fp_line
			(start 0.67945 -0.3048)
			(end 0.67945 0.3048)
			(stroke
				(width 0.1)
				(type default)
			)
			(layer "F.Fab")
		)
		(fp_line
			(start -0.67945 -0.305054)
			(end -0.12065 -0.305054)
			(stroke
				(width 0.1)
				(type default)
			)
			(layer "F.Fab")
		)
		(fp_line
			(start -0.12065 -0.305054)
			(end -0.12065 -0.2794)
			(stroke
				(width 0.1)
				(type default)
			)
			(layer "F.Fab")
		)
		(pad "1" smd circle
			(at -0.40005 0 270)
			(size 0 0)
			(layers "F.Cu" "F.Mask" "F.Paste")
			(net "P3V3_AUX")
		)
		(pad "2" smd circle
			(at 0.40005 0 270)
			(size 0 0)
			(layers "F.Cu" "F.Mask" "F.Paste")
			(net "BOOT_RDY_BUF_LED")
		)
	)
)
